(kicad_pcb
	(version 20260206)
	(generator "pcbnew")
	(generator_version "10.0")
	(general
		(thickness 1.6)
		(legacy_teardrops no)
	)
	(paper "A4")
	(title_block
		(title "v1-pdb — T6M_PDB_D_0927_0900.brd")
		(comment 1 "Open CloudServer (Microsoft) / footprint 315 of 321 (J16), pads 1-46 of 46")
	)
	(layers
		(0 "F.Cu" signal "TOP")
		(4 "In1.Cu" signal "GND")
		(6 "In2.Cu" signal "IN1")
		(8 "In3.Cu" signal "VCC")
		(10 "In4.Cu" signal "VCC1")
		(12 "In5.Cu" signal "IN2")
		(14 "In6.Cu" signal "GND1")
		(2 "B.Cu" signal "BOTTOM")
		(9 "F.Adhes" user "F.Adhesive")
		(11 "B.Adhes" user "B.Adhesive")
		(13 "F.Paste" user "Package Geometry/Pastemask Top")
		(15 "B.Paste" user "Package Geometry/Pastemask Bottom")
		(5 "F.SilkS" user "Ref Des/Silkscreen Top")
		(7 "B.SilkS" user "Ref Des/Silkscreen Bottom")
		(1 "F.Mask" user "Board Geometry/Soldermask Top")
		(3 "B.Mask" user "Board Geometry/Soldermask Bottom")
		(17 "Dwgs.User" user "User.Drawings")
		(19 "Cmts.User" user "User.Comments")
		(21 "Eco1.User" user "User.Eco1")
		(23 "Eco2.User" user "User.Eco2")
		(25 "Edge.Cuts" user "Board Geometry/Outline")
		(27 "Margin" user)
		(31 "F.CrtYd" user "Package Geometry/Place Bound Top")
		(29 "B.CrtYd" user "Package Geometry/Place Bound Bottom")
		(35 "F.Fab" user "Ref Des/Assembly Top")
		(33 "B.Fab" user "Ref Des/Assembly Bottom")
	)
	(footprint ""
		(layer "B.Cu")
		(at 44.03979 -408.31008 90)
		(property "Reference" "J16"
			(at 6.272784 -4.326636 0)
			(unlocked yes)
			(layer "B.SilkS")
			(effects
				(font
					(size 0.7874 0.5842)
					(thickness 0.1524)
				)
				(justify left mirror)
			)
		)
		(property "Value" ""
			(at 0 0 90)
			(layer "B.Fab")
			(effects
				(font
					(size 1.27 1.27)
				)
				(justify mirror)
			)
		)
		(duplicate_pad_numbers_are_jumpers no)
		(pad "" np_thru_hole circle
			(at -1.35001 -2.54)
			(size 2.5146 2.5146)
			(drill 2.5146)
			(layers "*.Cu" "*.Mask")
			(clearance 0.381)
			(thermal_gap 0.381)
		)
		(pad "" np_thru_hole circle
			(at 0 50.8)
			(size 2.5146 2.5146)
			(drill 2.5146)
			(layers "*.Cu" "*.Mask")
			(clearance 0.381)
			(thermal_gap 0.381)
		)
		(pad "P1" thru_hole rect
			(at 0 0)
			(size 1.1684 1.1684)
			(drill 0.762)
			(layers "*.Cu" "*.Mask")
			(remove_unused_layers no)
			(net "GND")
			(clearance 0.0508)
			(padstack
				(mode front_inner_back)
				(layer "Inner"
					(shape circle)
					(size 1.1684 1.1684)
					(clearance 0.0508)
				)
				(layer "B.Cu"
					(shape rect)
					(size 1.1684 1.1684)
					(thermal_gap 0.0508)
					(clearance 0.0508)
				)
			)
		)
		(pad "P2" thru_hole circle
			(at 0 2.54)
			(size 1.1684 1.1684)
			(drill 0.762)
			(layers "*.Cu" "*.Mask")
			(remove_unused_layers no)
			(net "GND")
			(clearance 0.0508)
			(thermal_gap 0.0508)
		)
		(pad "P3" thru_hole circle
			(at 0 5.08)
			(size 1.1684 1.1684)
			(drill 0.762)
			(layers "*.Cu" "*.Mask")
			(remove_unused_layers no)
			(net "GND")
			(clearance 0.0508)
			(thermal_gap 0.0508)
		)
		(pad "P4" thru_hole circle
			(at 0 7.62)
			(size 1.1684 1.1684)
			(drill 0.762)
			(layers "*.Cu" "*.Mask")
			(remove_unused_layers no)
			(net "GND")
			(clearance 0.0508)
			(thermal_gap 0.0508)
		)
		(pad "P5" thru_hole circle
			(at 0 10.16)
			(size 1.1684 1.1684)
			(drill 0.762)
			(layers "*.Cu" "*.Mask")
			(remove_unused_layers no)
			(net "GND")
			(clearance 0.0508)
			(thermal_gap 0.0508)
		)
		(pad "P6" thru_hole circle
			(at 0 12.7)
			(size 1.1684 1.1684)
			(drill 0.762)
			(layers "*.Cu" "*.Mask")
			(remove_unused_layers no)
			(net "GND")
			(clearance 0.0508)
			(thermal_gap 0.0508)
		)
		(pad "P7" thru_hole circle
			(at 0 15.24)
			(size 1.1684 1.1684)
			(drill 0.762)
			(layers "*.Cu" "*.Mask")
			(remove_unused_layers no)
			(net "GND")
			(clearance 0.0508)
			(thermal_gap 0.0508)
		)
		(pad "P8" thru_hole circle
			(at 0 17.78)
			(size 1.1684 1.1684)
			(drill 0.762)
			(layers "*.Cu" "*.Mask")
			(remove_unused_layers no)
			(net "GND")
			(clearance 0.0508)
			(thermal_gap 0.0508)
		)
		(pad "P9" thru_hole circle
			(at 0 20.32)
			(size 1.1684 1.1684)
			(drill 0.762)
			(layers "*.Cu" "*.Mask")
			(remove_unused_layers no)
			(net "P12V")
			(clearance 0.0508)
			(thermal_gap 0.0508)
		)
		(pad "P10" thru_hole circle
			(at 0 22.86)
			(size 1.1684 1.1684)
			(drill 0.762)
			(layers "*.Cu" "*.Mask")
			(remove_unused_layers no)
			(net "P12V")
			(clearance 0.0508)
			(thermal_gap 0.0508)
		)
		(pad "P11" thru_hole circle
			(at 0 25.4)
			(size 1.1684 1.1684)
			(drill 0.762)
			(layers "*.Cu" "*.Mask")
			(remove_unused_layers no)
			(net "P12V")
			(clearance 0.0508)
			(thermal_gap 0.0508)
		)
		(pad "P12" thru_hole circle
			(at 0 27.94)
			(size 1.1684 1.1684)
			(drill 0.762)
			(layers "*.Cu" "*.Mask")
			(remove_unused_layers no)
			(net "P12V")
			(clearance 0.0508)
			(thermal_gap 0.0508)
		)
		(pad "P13" thru_hole circle
			(at 0 30.48)
			(size 1.1684 1.1684)
			(drill 0.762)
			(layers "*.Cu" "*.Mask")
			(remove_unused_layers no)
			(net "P12V")
			(clearance 0.0508)
			(thermal_gap 0.0508)
		)
		(pad "P14" thru_hole circle
			(at 0 33.02)
			(size 1.1684 1.1684)
			(drill 0.762)
			(layers "*.Cu" "*.Mask")
			(remove_unused_layers no)
			(net "P12V")
			(clearance 0.0508)
			(thermal_gap 0.0508)
		)
		(pad "P15" thru_hole circle
			(at 0 35.56)
			(size 1.1684 1.1684)
			(drill 0.762)
			(layers "*.Cu" "*.Mask")
			(remove_unused_layers no)
			(net "P12V")
			(clearance 0.0508)
			(thermal_gap 0.0508)
		)
		(pad "P16" thru_hole circle
			(at 0 38.1)
			(size 1.1684 1.1684)
			(drill 0.762)
			(layers "*.Cu" "*.Mask")
			(remove_unused_layers no)
			(net "P12V")
			(clearance 0.0508)
			(thermal_gap 0.0508)
		)
		(pad "P17" thru_hole circle
			(at -2.70002 38.1)
			(size 1.1684 1.1684)
			(drill 0.762)
			(layers "*.Cu" "*.Mask")
			(remove_unused_layers no)
			(net "P12V")
			(clearance 0.0508)
			(thermal_gap 0.0508)
		)
		(pad "P18" thru_hole circle
			(at -2.70002 35.56)
			(size 1.1684 1.1684)
			(drill 0.762)
			(layers "*.Cu" "*.Mask")
			(remove_unused_layers no)
			(net "P12V")
			(clearance 0.0508)
			(thermal_gap 0.0508)
		)
		(pad "P19" thru_hole circle
			(at -2.70002 33.02)
			(size 1.1684 1.1684)
			(drill 0.762)
			(layers "*.Cu" "*.Mask")
			(remove_unused_layers no)
			(net "P12V")
			(clearance 0.0508)
			(thermal_gap 0.0508)
		)
		(pad "P20" thru_hole circle
			(at -2.70002 30.48)
			(size 1.1684 1.1684)
			(drill 0.762)
			(layers "*.Cu" "*.Mask")
			(remove_unused_layers no)
			(net "P12V")
			(clearance 0.0508)
			(thermal_gap 0.0508)
		)
		(pad "P21" thru_hole circle
			(at -2.70002 27.94)
			(size 1.1684 1.1684)
			(drill 0.762)
			(layers "*.Cu" "*.Mask")
			(remove_unused_layers no)
			(net "P12V")
			(clearance 0.0508)
			(thermal_gap 0.0508)
		)
		(pad "P22" thru_hole circle
			(at -2.70002 25.4)
			(size 1.1684 1.1684)
			(drill 0.762)
			(layers "*.Cu" "*.Mask")
			(remove_unused_layers no)
			(net "P12V")
			(clearance 0.0508)
			(thermal_gap 0.0508)
		)
		(pad "P23" thru_hole circle
			(at -2.70002 22.86)
			(size 1.1684 1.1684)
			(drill 0.762)
			(layers "*.Cu" "*.Mask")
			(remove_unused_layers no)
			(net "P12V")
			(clearance 0.0508)
			(thermal_gap 0.0508)
		)
		(pad "P24" thru_hole circle
			(at -2.70002 20.32)
			(size 1.1684 1.1684)
			(drill 0.762)
			(layers "*.Cu" "*.Mask")
			(remove_unused_layers no)
			(net "P12V")
			(clearance 0.0508)
			(thermal_gap 0.0508)
		)
		(pad "P25" thru_hole circle
			(at -2.70002 17.78)
			(size 1.1684 1.1684)
			(drill 0.762)
			(layers "*.Cu" "*.Mask")
			(remove_unused_layers no)
			(net "GND")
			(clearance 0.0508)
			(thermal_gap 0.0508)
		)
		(pad "P26" thru_hole circle
			(at -2.70002 15.24)
			(size 1.1684 1.1684)
			(drill 0.762)
			(layers "*.Cu" "*.Mask")
			(remove_unused_layers no)
			(net "GND")
			(clearance 0.0508)
			(thermal_gap 0.0508)
		)
		(pad "P27" thru_hole circle
			(at -2.70002 12.7)
			(size 1.1684 1.1684)
			(drill 0.762)
			(layers "*.Cu" "*.Mask")
			(remove_unused_layers no)
			(net "GND")
			(clearance 0.0508)
			(thermal_gap 0.0508)
		)
		(pad "P28" thru_hole circle
			(at -2.70002 10.16)
			(size 1.1684 1.1684)
			(drill 0.762)
			(layers "*.Cu" "*.Mask")
			(remove_unused_layers no)
			(net "GND")
			(clearance 0.0508)
			(thermal_gap 0.0508)
		)
		(pad "P29" thru_hole circle
			(at -2.70002 7.62)
			(size 1.1684 1.1684)
			(drill 0.762)
			(layers "*.Cu" "*.Mask")
			(remove_unused_layers no)
			(net "GND")
			(clearance 0.0508)
			(thermal_gap 0.0508)
		)
		(pad "P30" thru_hole circle
			(at -2.70002 5.08)
			(size 1.1684 1.1684)
			(drill 0.762)
			(layers "*.Cu" "*.Mask")
			(remove_unused_layers no)
			(net "GND")
			(clearance 0.0508)
			(thermal_gap 0.0508)
		)
		(pad "P31" thru_hole circle
			(at -2.70002 2.54)
			(size 1.1684 1.1684)
			(drill 0.762)
			(layers "*.Cu" "*.Mask")
			(remove_unused_layers no)
			(net "GND")
			(clearance 0.0508)
			(thermal_gap 0.0508)
		)
		(pad "P32" thru_hole circle
			(at -2.70002 0)
			(size 1.1684 1.1684)
			(drill 0.762)
			(layers "*.Cu" "*.Mask")
			(remove_unused_layers no)
			(net "GND")
			(clearance 0.0508)
			(thermal_gap 0.0508)
		)
		(pad "S1" thru_hole circle
			(at 0.55499 41.60012)
			(size 1.1684 1.1684)
			(drill 0.762)
			(layers "*.Cu" "*.Mask")
			(remove_unused_layers no)
			(net "T10_BLAD1_TXD")
			(clearance 0.0508)
			(thermal_gap 0.0508)
		)
		(pad "S2" thru_hole circle
			(at -0.71501 42.87012)
			(size 1.1684 1.1684)
			(drill 0.762)
			(layers "*.Cu" "*.Mask")
			(remove_unused_layers no)
			(net "T10_BLAD1_RXD")
			(clearance 0.0508)
			(thermal_gap 0.0508)
		)
		(pad "S3" thru_hole circle
			(at 0.55499 44.14012)
			(size 1.1684 1.1684)
			(drill 0.762)
			(layers "*.Cu" "*.Mask")
			(remove_unused_layers no)
			(net "T10_BLAD1_EN")
			(clearance 0.0508)
			(thermal_gap 0.0508)
		)
		(pad "S4" thru_hole circle
			(at -0.71501 45.41012)
			(size 1.1684 1.1684)
			(drill 0.762)
			(layers "*.Cu" "*.Mask")
			(remove_unused_layers no)
			(net "T10_BLAD2_EN")
			(clearance 0.0508)
			(thermal_gap 0.0508)
		)
		(pad "S5" thru_hole circle
			(at 0.55499 46.68012)
			(size 1.1684 1.1684)
			(drill 0.762)
			(layers "*.Cu" "*.Mask")
			(remove_unused_layers no)
			(net "T10_BLAD2_TXD")
			(clearance 0.0508)
			(thermal_gap 0.0508)
		)
		(pad "S6" thru_hole circle
			(at -0.71501 47.95012)
			(size 1.1684 1.1684)
			(drill 0.762)
			(layers "*.Cu" "*.Mask")
			(remove_unused_layers no)
			(net "T10_BLAD2_RXD")
			(clearance 0.0508)
			(thermal_gap 0.0508)
		)
		(pad "S7" thru_hole circle
			(at -3.25501 47.95012)
			(size 1.1684 1.1684)
			(drill 0.762)
			(layers "*.Cu" "*.Mask")
			(remove_unused_layers no)
			(net "T10_BLAD4_RXD")
			(clearance 0.0508)
			(thermal_gap 0.0508)
		)
		(pad "S8" thru_hole circle
			(at -1.98501 46.68012)
			(size 1.1684 1.1684)
			(drill 0.762)
			(layers "*.Cu" "*.Mask")
			(remove_unused_layers no)
			(net "T10_BLAD4_TXD")
			(clearance 0.0508)
			(thermal_gap 0.0508)
		)
		(pad "S9" thru_hole circle
			(at -3.25501 45.41012)
			(size 1.1684 1.1684)
			(drill 0.762)
			(layers "*.Cu" "*.Mask")
			(remove_unused_layers no)
			(net "T10_BLAD4_EN")
			(clearance 0.0508)
			(thermal_gap 0.0508)
		)
		(pad "S10" thru_hole circle
			(at -1.98501 44.14012)
			(size 1.1684 1.1684)
			(drill 0.762)
			(layers "*.Cu" "*.Mask")
			(remove_unused_layers no)
			(net "T10_BLAD3_EN")
			(clearance 0.0508)
			(thermal_gap 0.0508)
		)
		(pad "S11" thru_hole circle
			(at -3.25501 42.87012)
			(size 1.1684 1.1684)
			(drill 0.762)
			(layers "*.Cu" "*.Mask")
			(remove_unused_layers no)
			(net "T10_BLAD3_RXD")
			(clearance 0.0508)
			(thermal_gap 0.0508)
		)
		(pad "S12" thru_hole circle
			(at -1.98501 41.60012)
			(size 1.1684 1.1684)
			(drill 0.762)
			(layers "*.Cu" "*.Mask")
			(remove_unused_layers no)
			(net "T10_BLAD3_TXD")
			(clearance 0.0508)
			(thermal_gap 0.0508)
		)
	)
)
